# BASEBOARD_FAB2 (Tioga Pass) — schematic netlist excerpt (pin names and nets, part order shuffled) for the footprints in the layout excerpt that follows; sources: Cadence DE-HDL packaged netlist, KiCad conversion of Wiwynn_Tioga_Pass_MB.brd

R4G23  RES  0.0 5% CHIP  pkg 0402  page 221 : A = PWRGD_PVDDQ_ABC_R ; B = FM_PVTT_ABC_EN_R
R9A7  RES  2.21K 1% CHIP  pkg 0402  page 155 : A = P3V3_STBY ; B = SPA_SIN_SW_R
C2D16  CAP_A  22.0UF 4V 20% X6S  pkg 0603V  page 76 : A = PVCCIN_CPU1 ; B = GND

(kicad_pcb
	(version 20260206)
	(generator "pcbnew")
	(generator_version "10.0")
	(general
		(thickness 1.6)
		(legacy_teardrops no)
	)
	(paper "A4")
	(title_block
		(title "Wiwynn_Tioga_Pass_MB.brd")
		(comment 1 "Tioga Pass / footprints 1487-1489 of 4770")
	)
	(layers
		(0 "F.Cu" signal "TOP")
		(4 "In1.Cu" signal "L2GND")
		(6 "In2.Cu" signal "L3")
		(8 "In3.Cu" signal "L4GND")
		(10 "In4.Cu" signal "L5")
		(12 "In5.Cu" signal "L6GND")
		(14 "In6.Cu" signal "L7VCC")
		(16 "In7.Cu" signal "L8VCC")
		(18 "In8.Cu" signal "L9GND")
		(20 "In9.Cu" signal "L10")
		(22 "In10.Cu" signal "L11GND")
		(24 "In11.Cu" signal "L12")
		(26 "In12.Cu" signal "L13GND")
		(2 "B.Cu" signal "BOTTOM")
		(9 "F.Adhes" user "F.Adhesive")
		(11 "B.Adhes" user "B.Adhesive")
		(13 "F.Paste" user "Package Geometry/Pastemask Top")
		(15 "B.Paste" user "Package Geometry/Pastemask Bottom")
		(5 "F.SilkS" user "Ref Des/Silkscreen Top")
		(7 "B.SilkS" user "Ref Des/Silkscreen Bottom")
		(1 "F.Mask" user "Board Geometry/Soldermask Top")
		(3 "B.Mask" user "Board Geometry/Soldermask Bottom")
		(17 "Dwgs.User" user "User.Drawings")
		(19 "Cmts.User" user "User.Comments")
		(21 "Eco1.User" user "User.Eco1")
		(23 "Eco2.User" user "User.Eco2")
		(25 "Edge.Cuts" user "Board Geometry/Outline")
		(27 "Margin" user)
		(31 "F.CrtYd" user "Package Geometry/Place Bound Top")
		(29 "B.CrtYd" user "Package Geometry/Place Bound Bottom")
		(35 "F.Fab" user "Ref Des/Assembly Top")
		(33 "B.Fab" user "Ref Des/Assembly Bottom")
	)
	(footprint ""
		(layer "F.Cu")
		(at 491.426246 -152.15616 -90)
		(property "Reference" "R9A7"
			(at 0 0 270)
			(layer "F.SilkS")
			(hide yes)
			(effects
				(font
					(size 1.27 1.27)
				)
			)
		)
		(property "Value" ""
			(at 0 0 270)
			(layer "F.Fab")
			(effects
				(font
					(size 1.27 1.27)
				)
			)
		)
		(duplicate_pad_numbers_are_jumpers no)
		(fp_poly
			(pts
				(xy -0.2794 -0.1016) (xy 0.2794 -0.1016) (xy 0.2794 0.9906) (xy -0.2794 0.9906)
			)
			(stroke
				(width 0)
				(type default)
			)
			(fill no)
			(layer "F.CrtYd")
		)
		(fp_line
			(start -0.2794 0.9906)
			(end 0.2794 0.9906)
			(stroke
				(width 0.1)
				(type default)
			)
			(layer "F.Fab")
		)
		(fp_line
			(start 0.2794 0.9906)
			(end 0.2794 -0.1016)
			(stroke
				(width 0.1)
				(type default)
			)
			(layer "F.Fab")
		)
		(fp_line
			(start -0.2794 -0.1016)
			(end -0.2794 0.9906)
			(stroke
				(width 0.1)
				(type default)
			)
			(layer "F.Fab")
		)
		(fp_line
			(start 0.2794 -0.1016)
			(end -0.2794 -0.1016)
			(stroke
				(width 0.1)
				(type default)
			)
			(layer "F.Fab")
		)
		(pad "1" smd rect
			(at 0 0 270)
			(size 0.508 0.508)
			(layers "F.Cu" "F.Mask" "F.Paste")
			(net "P3V3_STBY")
		)
		(pad "2" smd rect
			(at 0 0.889 270)
			(size 0.508 0.508)
			(layers "F.Cu" "F.Mask" "F.Paste")
			(net "SPA_SIN_SW_R")
		)
		(zone
			(layer "F.Cu")
			(hatch none 0.5)
			(connect_pads
				(clearance 0)
			)
			(min_thickness 0.25)
			(keepout
				(tracks not_allowed)
				(vias allowed)
				(pads allowed)
				(copperpour not_allowed)
				(footprints allowed)
			)
			(placement
				(enabled no)
				(sheetname "")
			)
			(fill
				(thermal_gap 0.5)
				(thermal_bridge_width 0.5)
				(island_removal_mode 0)
			)
			(polygon
				(pts
					(xy 490.791246 -152.41016) (xy 490.791246 -151.90216) (xy 491.172246 -151.90216) (xy 491.172246 -152.41016)
				)
			)
		)
		(zone
			(layer "F.Cu")
			(hatch none 0.5)
			(connect_pads
				(clearance 0)
			)
			(min_thickness 0.25)
			(keepout
				(tracks allowed)
				(vias not_allowed)
				(pads allowed)
				(copperpour not_allowed)
				(footprints allowed)
			)
			(placement
				(enabled no)
				(sheetname "")
			)
			(fill
				(thermal_gap 0.5)
				(thermal_bridge_width 0.5)
				(island_removal_mode 0)
			)
			(polygon
				(pts
					(xy 491.172246 -152.41016) (xy 491.172246 -151.90216) (xy 490.791246 -151.90216) (xy 490.791246 -152.41016)
				)
			)
		)
	)
	(footprint ""
		(layer "F.Cu")
		(at 101.928168 -79.6036 180)
		(property "Reference" "C2D16"
			(at 0 0 180)
			(layer "F.SilkS")
			(hide yes)
			(effects
				(font
					(size 1.27 1.27)
				)
			)
		)
		(property "Value" ""
			(at 0 0 180)
			(layer "F.Fab")
			(effects
				(font
					(size 1.27 1.27)
				)
			)
		)
		(duplicate_pad_numbers_are_jumpers no)
		(fp_poly
			(pts
				(xy -0.4953 -0.2032) (xy 0.4953 -0.2032) (xy 0.4953 1.6002) (xy -0.4953 1.6002)
			)
			(stroke
				(width 0)
				(type default)
			)
			(fill no)
			(layer "F.CrtYd")
		)
		(fp_line
			(start 0.4953 1.6002)
			(end -0.4953 1.6002)
			(stroke
				(width 0.1)
				(type default)
			)
			(layer "F.Fab")
		)
		(fp_line
			(start 0.4953 -0.2032)
			(end 0.4953 1.6002)
			(stroke
				(width 0.1)
				(type default)
			)
			(layer "F.Fab")
		)
		(fp_line
			(start -0.4953 1.6002)
			(end -0.4953 -0.2032)
			(stroke
				(width 0.1)
				(type default)
			)
			(layer "F.Fab")
		)
		(fp_line
			(start -0.4953 -0.2032)
			(end 0.4953 -0.2032)
			(stroke
				(width 0.1)
				(type default)
			)
			(layer "F.Fab")
		)
		(pad "1" smd rect
			(at 0 0 180)
			(size 0.762 0.889)
			(layers "F.Cu" "F.Mask" "F.Paste")
			(net "PVCCIN_CPU1")
		)
		(pad "2" smd rect
			(at 0 1.397 180)
			(size 0.762 0.889)
			(layers "F.Cu" "F.Mask" "F.Paste")
			(net "GND")
		)
		(zone
			(layer "F.Cu")
			(hatch none 0.5)
			(connect_pads
				(clearance 0)
			)
			(min_thickness 0.25)
			(keepout
				(tracks not_allowed)
				(vias allowed)
				(pads allowed)
				(copperpour not_allowed)
				(footprints allowed)
			)
			(placement
				(enabled no)
				(sheetname "")
			)
			(fill
				(thermal_gap 0.5)
				(thermal_bridge_width 0.5)
				(island_removal_mode 0)
			)
			(polygon
				(pts
					(xy 102.309168 -80.0481) (xy 101.547168 -80.0481) (xy 101.547168 -80.5561) (xy 102.309168 -80.5561)
				)
			)
		)
	)
	(footprint ""
		(layer "F.Cu")
		(at 180.3781 2.4003 180)
		(property "Reference" "R4G23"
			(at 0 0 180)
			(layer "F.SilkS")
			(hide yes)
			(effects
				(font
					(size 1.27 1.27)
				)
			)
		)
		(property "Value" ""
			(at 0 0 180)
			(layer "F.Fab")
			(effects
				(font
					(size 1.27 1.27)
				)
			)
		)
		(duplicate_pad_numbers_are_jumpers no)
		(fp_poly
			(pts
				(xy -0.2794 -0.1016) (xy 0.2794 -0.1016) (xy 0.2794 0.9906) (xy -0.2794 0.9906)
			)
			(stroke
				(width 0)
				(type default)
			)
			(fill no)
			(layer "F.CrtYd")
		)
		(fp_line
			(start 0.2794 0.9906)
			(end 0.2794 -0.1016)
			(stroke
				(width 0.1)
				(type default)
			)
			(layer "F.Fab")
		)
		(fp_line
			(start 0.2794 -0.1016)
			(end -0.2794 -0.1016)
			(stroke
				(width 0.1)
				(type default)
			)
			(layer "F.Fab")
		)
		(fp_line
			(start -0.2794 0.9906)
			(end 0.2794 0.9906)
			(stroke
				(width 0.1)
				(type default)
			)
			(layer "F.Fab")
		)
		(fp_line
			(start -0.2794 -0.1016)
			(end -0.2794 0.9906)
			(stroke
				(width 0.1)
				(type default)
			)
			(layer "F.Fab")
		)
		(pad "1" smd rect
			(at 0 0 180)
			(size 0.508 0.508)
			(layers "F.Cu" "F.Mask" "F.Paste")
			(net "PWRGD_PVDDQ_ABC_R")
		)
		(pad "2" smd rect
			(at 0 0.889 180)
			(size 0.508 0.508)
			(layers "F.Cu" "F.Mask" "F.Paste")
			(net "FM_PVTT_ABC_EN_R")
		)
		(zone
			(layer "F.Cu")
			(hatch none 0.5)
			(connect_pads
				(clearance 0)
			)
			(min_thickness 0.25)
			(keepout
				(tracks not_allowed)
				(vias allowed)
				(pads allowed)
				(copperpour not_allowed)
				(footprints allowed)
			)
			(placement
				(enabled no)
				(sheetname "")
			)
			(fill
				(thermal_gap 0.5)
				(thermal_bridge_width 0.5)
				(island_removal_mode 0)
			)
			(polygon
				(pts
					(xy 180.6321 1.7653) (xy 180.1241 1.7653) (xy 180.1241 2.1463) (xy 180.6321 2.1463)
				)
			)
		)
		(zone
			(layer "F.Cu")
			(hatch none 0.5)
			(connect_pads
				(clearance 0)
			)
			(min_thickness 0.25)
			(keepout
				(tracks allowed)
				(vias not_allowed)
				(pads allowed)
				(copperpour not_allowed)
				(footprints allowed)
			)
			(placement
				(enabled no)
				(sheetname "")
			)
			(fill
				(thermal_gap 0.5)
				(thermal_bridge_width 0.5)
				(island_removal_mode 0)
			)
			(polygon
				(pts
					(xy 180.6321 2.1463) (xy 180.1241 2.1463) (xy 180.1241 1.7653) (xy 180.6321 1.7653)
				)
			)
		)
	)
)
